(kicad_pcb
	(version 20260206)
	(generator "pcbnew")
	(generator_version "10.0")
	(general
		(thickness 1.6)
		(legacy_teardrops no)
	)
	(paper "A4")
	(title_block
		(title "03242023_DA0F0TMBIJ0_F0T_Motherboard_J_brd_V01_OCP.brd")
		(comment 1 "Grand Teton / footprints 2925-2931 of 6105")
	)
	(layers
		(0 "F.Cu" signal "TOP")
		(4 "In1.Cu" signal "GND")
		(6 "In2.Cu" signal "IN1")
		(8 "In3.Cu" signal "GND1")
		(10 "In4.Cu" signal "IN2")
		(12 "In5.Cu" signal "GND2")
		(14 "In6.Cu" signal "IN3")
		(16 "In7.Cu" signal "GND3")
		(18 "In8.Cu" signal "VCC")
		(20 "In9.Cu" signal "VCC1")
		(22 "In10.Cu" signal "GND4")
		(24 "In11.Cu" signal "IN4")
		(26 "In12.Cu" signal "GND5")
		(28 "In13.Cu" signal "IN5")
		(30 "In14.Cu" signal "GND6")
		(32 "In15.Cu" signal "IN6")
		(34 "In16.Cu" signal "GND7")
		(2 "B.Cu" signal "BOTTOM")
		(9 "F.Adhes" user "F.Adhesive")
		(11 "B.Adhes" user "B.Adhesive")
		(13 "F.Paste" user "Package Geometry/Pastemask Top")
		(15 "B.Paste" user "Package Geometry/Pastemask Bottom")
		(5 "F.SilkS" user "Ref Des/Silkscreen Top")
		(7 "B.SilkS" user "Ref Des/Silkscreen Bottom")
		(1 "F.Mask" user "Board Geometry/Soldermask Top")
		(3 "B.Mask" user "Board Geometry/Soldermask Bottom")
		(17 "Dwgs.User" user "User.Drawings")
		(19 "Cmts.User" user "User.Comments")
		(21 "Eco1.User" user "User.Eco1")
		(23 "Eco2.User" user "User.Eco2")
		(25 "Edge.Cuts" user "Board Geometry/Outline")
		(27 "Margin" user)
		(31 "F.CrtYd" user "Package Geometry/Place Bound Top")
		(29 "B.CrtYd" user "Package Geometry/Place Bound Bottom")
		(35 "F.Fab" user "Ref Des/Assembly Top")
		(33 "B.Fab" user "Ref Des/Assembly Bottom")
	)
	(footprint ""
		(layer "F.Cu")
		(at 453.719946 -108.059728)
		(property "Reference" "R1905"
			(at 0 0 0)
			(layer "F.SilkS")
			(hide yes)
			(effects
				(font
					(size 1.27 1.27)
				)
			)
		)
		(property "Value" ""
			(at 0 0 0)
			(layer "F.Fab")
			(effects
				(font
					(size 1.27 1.27)
				)
			)
		)
		(duplicate_pad_numbers_are_jumpers no)
		(fp_line
			(start -0.7874 -0.4064)
			(end 0.7874 -0.4064)
			(stroke
				(width 0.1524)
				(type default)
			)
			(layer "F.SilkS")
		)
		(fp_line
			(start -0.7874 0.4064)
			(end -0.7874 -0.4064)
			(stroke
				(width 0.1524)
				(type default)
			)
			(layer "F.SilkS")
		)
		(fp_line
			(start 0.7874 -0.4064)
			(end 0.7874 0.4064)
			(stroke
				(width 0.1524)
				(type default)
			)
			(layer "F.SilkS")
		)
		(fp_line
			(start 0.7874 0.4064)
			(end -0.7874 0.4064)
			(stroke
				(width 0.1524)
				(type default)
			)
			(layer "F.SilkS")
		)
		(fp_line
			(start -0.67945 -0.305054)
			(end -0.12065 -0.305054)
			(stroke
				(width 0.1)
				(type default)
			)
			(layer "F.Fab")
		)
		(fp_line
			(start -0.67945 0.3048)
			(end -0.67945 -0.305054)
			(stroke
				(width 0.1)
				(type default)
			)
			(layer "F.Fab")
		)
		(fp_line
			(start -0.12065 -0.305054)
			(end -0.12065 -0.2794)
			(stroke
				(width 0.1)
				(type default)
			)
			(layer "F.Fab")
		)
		(fp_line
			(start -0.12065 -0.2794)
			(end 0.12065 -0.2794)
			(stroke
				(width 0.1)
				(type default)
			)
			(layer "F.Fab")
		)
		(fp_line
			(start -0.12065 0.2794)
			(end -0.12065 0.3048)
			(stroke
				(width 0.1)
				(type default)
			)
			(layer "F.Fab")
		)
		(fp_line
			(start -0.12065 0.3048)
			(end -0.67945 0.3048)
			(stroke
				(width 0.1)
				(type default)
			)
			(layer "F.Fab")
		)
		(fp_line
			(start 0.120396 0.2794)
			(end -0.12065 0.2794)
			(stroke
				(width 0.1)
				(type default)
			)
			(layer "F.Fab")
		)
		(fp_line
			(start 0.120396 0.3048)
			(end 0.120396 0.2794)
			(stroke
				(width 0.1)
				(type default)
			)
			(layer "F.Fab")
		)
		(fp_line
			(start 0.12065 -0.3048)
			(end 0.67945 -0.3048)
			(stroke
				(width 0.1)
				(type default)
			)
			(layer "F.Fab")
		)
		(fp_line
			(start 0.12065 -0.2794)
			(end 0.12065 -0.3048)
			(stroke
				(width 0.1)
				(type default)
			)
			(layer "F.Fab")
		)
		(fp_line
			(start 0.67945 -0.3048)
			(end 0.67945 0.3048)
			(stroke
				(width 0.1)
				(type default)
			)
			(layer "F.Fab")
		)
		(fp_line
			(start 0.67945 0.3048)
			(end 0.120396 0.3048)
			(stroke
				(width 0.1)
				(type default)
			)
			(layer "F.Fab")
		)
		(pad "1" smd circle
			(at -0.40005 0)
			(size 0 0)
			(layers "F.Cu" "F.Mask" "F.Paste")
			(net "P3V3_AUX")
		)
		(pad "2" smd circle
			(at 0.40005 0)
			(size 0 0)
			(layers "F.Cu" "F.Mask" "F.Paste")
			(net "OCP_SFF_PRSNT0_R_N")
		)
	)
	(footprint ""
		(layer "F.Cu")
		(at 7.42188 -54.955948)
		(property "Reference" "R2996"
			(at 0 0 0)
			(layer "F.SilkS")
			(hide yes)
			(effects
				(font
					(size 1.27 1.27)
				)
			)
		)
		(property "Value" ""
			(at 0 0 0)
			(layer "F.Fab")
			(effects
				(font
					(size 1.27 1.27)
				)
			)
		)
		(duplicate_pad_numbers_are_jumpers no)
		(fp_line
			(start -0.7874 -0.4064)
			(end 0.7874 -0.4064)
			(stroke
				(width 0.1524)
				(type default)
			)
			(layer "F.SilkS")
		)
		(fp_line
			(start -0.7874 0.4064)
			(end -0.7874 -0.4064)
			(stroke
				(width 0.1524)
				(type default)
			)
			(layer "F.SilkS")
		)
		(fp_line
			(start 0.7874 -0.4064)
			(end 0.7874 0.4064)
			(stroke
				(width 0.1524)
				(type default)
			)
			(layer "F.SilkS")
		)
		(fp_line
			(start 0.7874 0.4064)
			(end -0.7874 0.4064)
			(stroke
				(width 0.1524)
				(type default)
			)
			(layer "F.SilkS")
		)
		(fp_line
			(start -0.67945 -0.305054)
			(end -0.12065 -0.305054)
			(stroke
				(width 0.1)
				(type default)
			)
			(layer "F.Fab")
		)
		(fp_line
			(start -0.67945 0.3048)
			(end -0.67945 -0.305054)
			(stroke
				(width 0.1)
				(type default)
			)
			(layer "F.Fab")
		)
		(fp_line
			(start -0.12065 -0.305054)
			(end -0.12065 -0.2794)
			(stroke
				(width 0.1)
				(type default)
			)
			(layer "F.Fab")
		)
		(fp_line
			(start -0.12065 -0.2794)
			(end 0.12065 -0.2794)
			(stroke
				(width 0.1)
				(type default)
			)
			(layer "F.Fab")
		)
		(fp_line
			(start -0.12065 0.2794)
			(end -0.12065 0.3048)
			(stroke
				(width 0.1)
				(type default)
			)
			(layer "F.Fab")
		)
		(fp_line
			(start -0.12065 0.3048)
			(end -0.67945 0.3048)
			(stroke
				(width 0.1)
				(type default)
			)
			(layer "F.Fab")
		)
		(fp_line
			(start 0.120396 0.2794)
			(end -0.12065 0.2794)
			(stroke
				(width 0.1)
				(type default)
			)
			(layer "F.Fab")
		)
		(fp_line
			(start 0.120396 0.3048)
			(end 0.120396 0.2794)
			(stroke
				(width 0.1)
				(type default)
			)
			(layer "F.Fab")
		)
		(fp_line
			(start 0.12065 -0.3048)
			(end 0.67945 -0.3048)
			(stroke
				(width 0.1)
				(type default)
			)
			(layer "F.Fab")
		)
		(fp_line
			(start 0.12065 -0.2794)
			(end 0.12065 -0.3048)
			(stroke
				(width 0.1)
				(type default)
			)
			(layer "F.Fab")
		)
		(fp_line
			(start 0.67945 -0.3048)
			(end 0.67945 0.3048)
			(stroke
				(width 0.1)
				(type default)
			)
			(layer "F.Fab")
		)
		(fp_line
			(start 0.67945 0.3048)
			(end 0.120396 0.3048)
			(stroke
				(width 0.1)
				(type default)
			)
			(layer "F.Fab")
		)
		(pad "1" smd circle
			(at -0.40005 0)
			(size 0 0)
			(layers "F.Cu" "F.Mask" "F.Paste")
			(net "SMB_SML1_PMBUS_3V3AUX_PCH_SDA")
		)
		(pad "2" smd circle
			(at 0.40005 0)
			(size 0 0)
			(layers "F.Cu" "F.Mask" "F.Paste")
			(net "SMB_SML1_PMBUS_HSC_SDA_R3")
		)
	)
	(footprint ""
		(layer "F.Cu")
		(at 135.02894 -347.509846 -90)
		(property "Reference" "PC1362"
			(at 0 0 270)
			(layer "F.SilkS")
			(hide yes)
			(effects
				(font
					(size 1.27 1.27)
				)
			)
		)
		(property "Value" ""
			(at 0 0 270)
			(layer "F.Fab")
			(effects
				(font
					(size 1.27 1.27)
				)
			)
		)
		(duplicate_pad_numbers_are_jumpers no)
		(fp_line
			(start -0.7874 0.4064)
			(end -0.7874 -0.4064)
			(stroke
				(width 0.1524)
				(type default)
			)
			(layer "F.SilkS")
		)
		(fp_line
			(start 0.7874 0.4064)
			(end -0.7874 0.4064)
			(stroke
				(width 0.1524)
				(type default)
			)
			(layer "F.SilkS")
		)
		(fp_line
			(start -0.7874 -0.4064)
			(end 0.7874 -0.4064)
			(stroke
				(width 0.1524)
				(type default)
			)
			(layer "F.SilkS")
		)
		(fp_line
			(start 0.7874 -0.4064)
			(end 0.7874 0.4064)
			(stroke
				(width 0.1524)
				(type default)
			)
			(layer "F.SilkS")
		)
		(fp_line
			(start -0.67945 0.3048)
			(end -0.67945 -0.305054)
			(stroke
				(width 0.1)
				(type default)
			)
			(layer "F.Fab")
		)
		(fp_line
			(start -0.12065 0.3048)
			(end -0.67945 0.3048)
			(stroke
				(width 0.1)
				(type default)
			)
			(layer "F.Fab")
		)
		(fp_line
			(start 0.120396 0.3048)
			(end 0.120396 0.2794)
			(stroke
				(width 0.1)
				(type default)
			)
			(layer "F.Fab")
		)
		(fp_line
			(start 0.67945 0.3048)
			(end 0.120396 0.3048)
			(stroke
				(width 0.1)
				(type default)
			)
			(layer "F.Fab")
		)
		(fp_line
			(start -0.12065 0.2794)
			(end -0.12065 0.3048)
			(stroke
				(width 0.1)
				(type default)
			)
			(layer "F.Fab")
		)
		(fp_line
			(start 0.120396 0.2794)
			(end -0.12065 0.2794)
			(stroke
				(width 0.1)
				(type default)
			)
			(layer "F.Fab")
		)
		(fp_line
			(start -0.12065 -0.2794)
			(end 0.12065 -0.2794)
			(stroke
				(width 0.1)
				(type default)
			)
			(layer "F.Fab")
		)
		(fp_line
			(start 0.12065 -0.2794)
			(end 0.12065 -0.3048)
			(stroke
				(width 0.1)
				(type default)
			)
			(layer "F.Fab")
		)
		(fp_line
			(start 0.12065 -0.3048)
			(end 0.67945 -0.3048)
			(stroke
				(width 0.1)
				(type default)
			)
			(layer "F.Fab")
		)
		(fp_line
			(start 0.67945 -0.3048)
			(end 0.67945 0.3048)
			(stroke
				(width 0.1)
				(type default)
			)
			(layer "F.Fab")
		)
		(fp_line
			(start -0.67945 -0.305054)
			(end -0.12065 -0.305054)
			(stroke
				(width 0.1)
				(type default)
			)
			(layer "F.Fab")
		)
		(fp_line
			(start -0.12065 -0.305054)
			(end -0.12065 -0.2794)
			(stroke
				(width 0.1)
				(type default)
			)
			(layer "F.Fab")
		)
		(pad "1" smd circle
			(at -0.40005 0 270)
			(size 0 0)
			(layers "F.Cu" "F.Mask" "F.Paste")
			(net "GND")
		)
		(pad "2" smd circle
			(at 0.40005 0 270)
			(size 0 0)
			(layers "F.Cu" "F.Mask" "F.Paste")
			(net "PVCCIN_CPU1_VREF")
		)
	)
	(footprint ""
		(layer "F.Cu")
		(at 7.42188 -61.051948 180)
		(property "Reference" "R581"
			(at 0 0 180)
			(layer "F.SilkS")
			(hide yes)
			(effects
				(font
					(size 1.27 1.27)
				)
			)
		)
		(property "Value" ""
			(at 0 0 180)
			(layer "F.Fab")
			(effects
				(font
					(size 1.27 1.27)
				)
			)
		)
		(duplicate_pad_numbers_are_jumpers no)
		(fp_line
			(start 0.7874 0.4064)
			(end -0.7874 0.4064)
			(stroke
				(width 0.1524)
				(type default)
			)
			(layer "F.SilkS")
		)
		(fp_line
			(start 0.7874 -0.4064)
			(end 0.7874 0.4064)
			(stroke
				(width 0.1524)
				(type default)
			)
			(layer "F.SilkS")
		)
		(fp_line
			(start -0.7874 0.4064)
			(end -0.7874 -0.4064)
			(stroke
				(width 0.1524)
				(type default)
			)
			(layer "F.SilkS")
		)
		(fp_line
			(start -0.7874 -0.4064)
			(end 0.7874 -0.4064)
			(stroke
				(width 0.1524)
				(type default)
			)
			(layer "F.SilkS")
		)
		(fp_line
			(start 0.67945 0.3048)
			(end 0.120396 0.3048)
			(stroke
				(width 0.1)
				(type default)
			)
			(layer "F.Fab")
		)
		(fp_line
			(start 0.67945 -0.3048)
			(end 0.67945 0.3048)
			(stroke
				(width 0.1)
				(type default)
			)
			(layer "F.Fab")
		)
		(fp_line
			(start 0.12065 -0.2794)
			(end 0.12065 -0.3048)
			(stroke
				(width 0.1)
				(type default)
			)
			(layer "F.Fab")
		)
		(fp_line
			(start 0.12065 -0.3048)
			(end 0.67945 -0.3048)
			(stroke
				(width 0.1)
				(type default)
			)
			(layer "F.Fab")
		)
		(fp_line
			(start 0.120396 0.3048)
			(end 0.120396 0.2794)
			(stroke
				(width 0.1)
				(type default)
			)
			(layer "F.Fab")
		)
		(fp_line
			(start 0.120396 0.2794)
			(end -0.12065 0.2794)
			(stroke
				(width 0.1)
				(type default)
			)
			(layer "F.Fab")
		)
		(fp_line
			(start -0.12065 0.3048)
			(end -0.67945 0.3048)
			(stroke
				(width 0.1)
				(type default)
			)
			(layer "F.Fab")
		)
		(fp_line
			(start -0.12065 0.2794)
			(end -0.12065 0.3048)
			(stroke
				(width 0.1)
				(type default)
			)
			(layer "F.Fab")
		)
		(fp_line
			(start -0.12065 -0.2794)
			(end 0.12065 -0.2794)
			(stroke
				(width 0.1)
				(type default)
			)
			(layer "F.Fab")
		)
		(fp_line
			(start -0.12065 -0.305054)
			(end -0.12065 -0.2794)
			(stroke
				(width 0.1)
				(type default)
			)
			(layer "F.Fab")
		)
		(fp_line
			(start -0.67945 0.3048)
			(end -0.67945 -0.305054)
			(stroke
				(width 0.1)
				(type default)
			)
			(layer "F.Fab")
		)
		(fp_line
			(start -0.67945 -0.305054)
			(end -0.12065 -0.305054)
			(stroke
				(width 0.1)
				(type default)
			)
			(layer "F.Fab")
		)
		(pad "1" smd circle
			(at -0.40005 0 180)
			(size 0 0)
			(layers "F.Cu" "F.Mask" "F.Paste")
			(net "SMB_SML0_3V3AUX_SCL")
		)
		(pad "2" smd circle
			(at 0.40005 0 180)
			(size 0 0)
			(layers "F.Cu" "F.Mask" "F.Paste")
			(net "SMB_SML0_3V3AUX_PCH_SCL")
		)
	)
	(footprint ""
		(layer "F.Cu")
		(at 58.058558 -402.371052 -90)
		(property "Reference" "C717"
			(at 0 0 270)
			(layer "F.SilkS")
			(hide yes)
			(effects
				(font
					(size 1.27 1.27)
				)
			)
		)
		(property "Value" ""
			(at 0 0 270)
			(layer "F.Fab")
			(effects
				(font
					(size 1.27 1.27)
				)
			)
		)
		(duplicate_pad_numbers_are_jumpers no)
		(fp_line
			(start -0.299974 0.150114)
			(end -0.299974 -0.150114)
			(stroke
				(width 0.1)
				(type default)
			)
			(layer "F.Fab")
		)
		(fp_line
			(start 0.299974 0.150114)
			(end -0.299974 0.150114)
			(stroke
				(width 0.1)
				(type default)
			)
			(layer "F.Fab")
		)
		(fp_line
			(start -0.299974 -0.150114)
			(end 0.299974 -0.150114)
			(stroke
				(width 0.1)
				(type default)
			)
			(layer "F.Fab")
		)
		(fp_line
			(start 0.299974 -0.150114)
			(end 0.299974 0.150114)
			(stroke
				(width 0.1)
				(type default)
			)
			(layer "F.Fab")
		)
		(pad "1" smd rect
			(at -0.2667 0 270)
			(size 0.3048 0.381)
			(layers "F.Cu" "F.Mask" "F.Paste")
			(net "P5E_CPU1_PE0_TX_C_DP<12>")
		)
		(pad "2" smd rect
			(at 0.2667 0 270)
			(size 0.3048 0.381)
			(layers "F.Cu" "F.Mask" "F.Paste")
			(net "P5E_CPU1_PE0_TX_DP<12>")
		)
	)
	(footprint ""
		(layer "F.Cu")
		(at 105.306114 -260.36524 -90)
		(property "Reference" "C437"
			(at 0 0 270)
			(layer "F.SilkS")
			(hide yes)
			(effects
				(font
					(size 1.27 1.27)
				)
			)
		)
		(property "Value" ""
			(at 0 0 270)
			(layer "F.Fab")
			(effects
				(font
					(size 1.27 1.27)
				)
			)
		)
		(duplicate_pad_numbers_are_jumpers no)
		(fp_line
			(start -0.7874 0.4064)
			(end -0.7874 -0.4064)
			(stroke
				(width 0.1524)
				(type default)
			)
			(layer "F.SilkS")
		)
		(fp_line
			(start 0.7874 0.4064)
			(end -0.7874 0.4064)
			(stroke
				(width 0.1524)
				(type default)
			)
			(layer "F.SilkS")
		)
		(fp_line
			(start -0.7874 -0.4064)
			(end 0.7874 -0.4064)
			(stroke
				(width 0.1524)
				(type default)
			)
			(layer "F.SilkS")
		)
		(fp_line
			(start 0.7874 -0.4064)
			(end 0.7874 0.4064)
			(stroke
				(width 0.1524)
				(type default)
			)
			(layer "F.SilkS")
		)
		(fp_line
			(start -0.67945 0.3048)
			(end -0.67945 -0.305054)
			(stroke
				(width 0.1)
				(type default)
			)
			(layer "F.Fab")
		)
		(fp_line
			(start -0.12065 0.3048)
			(end -0.67945 0.3048)
			(stroke
				(width 0.1)
				(type default)
			)
			(layer "F.Fab")
		)
		(fp_line
			(start 0.120396 0.3048)
			(end 0.120396 0.2794)
			(stroke
				(width 0.1)
				(type default)
			)
			(layer "F.Fab")
		)
		(fp_line
			(start 0.67945 0.3048)
			(end 0.120396 0.3048)
			(stroke
				(width 0.1)
				(type default)
			)
			(layer "F.Fab")
		)
		(fp_line
			(start -0.12065 0.2794)
			(end -0.12065 0.3048)
			(stroke
				(width 0.1)
				(type default)
			)
			(layer "F.Fab")
		)
		(fp_line
			(start 0.120396 0.2794)
			(end -0.12065 0.2794)
			(stroke
				(width 0.1)
				(type default)
			)
			(layer "F.Fab")
		)
		(fp_line
			(start -0.12065 -0.2794)
			(end 0.12065 -0.2794)
			(stroke
				(width 0.1)
				(type default)
			)
			(layer "F.Fab")
		)
		(fp_line
			(start 0.12065 -0.2794)
			(end 0.12065 -0.3048)
			(stroke
				(width 0.1)
				(type default)
			)
			(layer "F.Fab")
		)
		(fp_line
			(start 0.12065 -0.3048)
			(end 0.67945 -0.3048)
			(stroke
				(width 0.1)
				(type default)
			)
			(layer "F.Fab")
		)
		(fp_line
			(start 0.67945 -0.3048)
			(end 0.67945 0.3048)
			(stroke
				(width 0.1)
				(type default)
			)
			(layer "F.Fab")
		)
		(fp_line
			(start -0.67945 -0.305054)
			(end -0.12065 -0.305054)
			(stroke
				(width 0.1)
				(type default)
			)
			(layer "F.Fab")
		)
		(fp_line
			(start -0.12065 -0.305054)
			(end -0.12065 -0.2794)
			(stroke
				(width 0.1)
				(type default)
			)
			(layer "F.Fab")
		)
		(pad "1" smd circle
			(at -0.40005 0 270)
			(size 0 0)
			(layers "F.Cu" "F.Mask" "F.Paste")
			(net "PVCCFA_EHV_FIVRA_CPU1")
		)
		(pad "2" smd circle
			(at 0.40005 0 270)
			(size 0 0)
			(layers "F.Cu" "F.Mask" "F.Paste")
			(net "GND")
		)
	)
	(footprint ""
		(layer "F.Cu")
		(at 31.307278 -138.01979 90)
		(property "Reference" "PR4243"
			(at 0 0 90)
			(layer "F.SilkS")
			(hide yes)
			(effects
				(font
					(size 1.27 1.27)
				)
			)
		)
		(property "Value" ""
			(at 0 0 90)
			(layer "F.Fab")
			(effects
				(font
					(size 1.27 1.27)
				)
			)
		)
		(duplicate_pad_numbers_are_jumpers no)
		(fp_line
			(start 0.7874 -0.4064)
			(end 0.7874 0.4064)
			(stroke
				(width 0.1524)
				(type default)
			)
			(layer "F.SilkS")
		)
		(fp_line
			(start -0.7874 -0.4064)
			(end 0.7874 -0.4064)
			(stroke
				(width 0.1524)
				(type default)
			)
			(layer "F.SilkS")
		)
		(fp_line
			(start 0.7874 0.4064)
			(end -0.7874 0.4064)
			(stroke
				(width 0.1524)
				(type default)
			)
			(layer "F.SilkS")
		)
		(fp_line
			(start -0.7874 0.4064)
			(end -0.7874 -0.4064)
			(stroke
				(width 0.1524)
				(type default)
			)
			(layer "F.SilkS")
		)
		(fp_line
			(start -0.12065 -0.305054)
			(end -0.12065 -0.2794)
			(stroke
				(width 0.1)
				(type default)
			)
			(layer "F.Fab")
		)
		(fp_line
			(start -0.67945 -0.305054)
			(end -0.12065 -0.305054)
			(stroke
				(width 0.1)
				(type default)
			)
			(layer "F.Fab")
		)
		(fp_line
			(start 0.67945 -0.3048)
			(end 0.67945 0.3048)
			(stroke
				(width 0.1)
				(type default)
			)
			(layer "F.Fab")
		)
		(fp_line
			(start 0.12065 -0.3048)
			(end 0.67945 -0.3048)
			(stroke
				(width 0.1)
				(type default)
			)
			(layer "F.Fab")
		)
		(fp_line
			(start 0.12065 -0.2794)
			(end 0.12065 -0.3048)
			(stroke
				(width 0.1)
				(type default)
			)
			(layer "F.Fab")
		)
		(fp_line
			(start -0.12065 -0.2794)
			(end 0.12065 -0.2794)
			(stroke
				(width 0.1)
				(type default)
			)
			(layer "F.Fab")
		)
		(fp_line
			(start 0.120396 0.2794)
			(end -0.12065 0.2794)
			(stroke
				(width 0.1)
				(type default)
			)
			(layer "F.Fab")
		)
		(fp_line
			(start -0.12065 0.2794)
			(end -0.12065 0.3048)
			(stroke
				(width 0.1)
				(type default)
			)
			(layer "F.Fab")
		)
		(fp_line
			(start 0.67945 0.3048)
			(end 0.120396 0.3048)
			(stroke
				(width 0.1)
				(type default)
			)
			(layer "F.Fab")
		)
		(fp_line
			(start 0.120396 0.3048)
			(end 0.120396 0.2794)
			(stroke
				(width 0.1)
				(type default)
			)
			(layer "F.Fab")
		)
		(fp_line
			(start -0.12065 0.3048)
			(end -0.67945 0.3048)
			(stroke
				(width 0.1)
				(type default)
			)
			(layer "F.Fab")
		)
		(fp_line
			(start -0.67945 0.3048)
			(end -0.67945 -0.305054)
			(stroke
				(width 0.1)
				(type default)
			)
			(layer "F.Fab")
		)
		(pad "1" smd circle
			(at -0.40005 0 90)
			(size 0 0)
			(layers "F.Cu" "F.Mask" "F.Paste")
			(net "NC_PVCCINFAON_CPU1_ACSP4")
		)
		(pad "2" smd circle
			(at 0.40005 0 90)
			(size 0 0)
			(layers "F.Cu" "F.Mask" "F.Paste")
			(net "GND")
		)
	)
)
